#ISCELL
  mstr_misc prelim *
  *
#ISCELL
  mstr_symbols bom_note *
  *
#ISCELL
  mstr_symbols cad_note *
  *
#ISCELL
  mstr_symbols design_note *
  *
#ISCELL
  mstr_symbols intel_corp_bpage *
  *
#ISCELL
  mstr_standard offpage *
  page55_i10
#ISCELL
  mstr_standard offpage *
  page55_i100
#ISCELL
  mstr_standard offpage *
  page55_i101
#ISCELL
  mstr_standard offpage *
  page55_i102
#ISCELL
  mstr_standard offpage *
  page55_i103
#ISCELL
  mstr_standard offpage *
  page55_i108
#ISCELL
  mstr_standard offpage *
  page55_i109
#CELL
  mstr_discrete res *
  page55_i115
#CELL
  mstr_discrete res *
  page55_i116
#CELL
  mstr_discrete res *
  page55_i117
#CELL
  mstr_discrete res *
  page55_i118
#CELL
  mstr_discrete res *
  page55_i119
#ISCELL
  mstr_symbols gnd *
  page55_i121
#ISCELL
  mstr_symbols gnd *
  page55_i122
#CELL
  mstr_discrete res *
  page55_i123
#CELL
  mstr_discrete res *
  page55_i124
#CELL
  mstr_discrete res *
  page55_i125
#CELL
  mstr_discrete res *
  page55_i126
#ISCELL
  mstr_standard offpage *
  page55_i13
#ISCELL
  mstr_standard offpage *
  page55_i132
#ISCELL
  mstr_standard offpage *
  page55_i133
#ISCELL
  mstr_standard offpage *
  page55_i134
#ISCELL
  mstr_standard offpage *
  page55_i135
#ISCELL
  mstr_standard offpage *
  page55_i138
#ISCELL
  mstr_standard offpage *
  page55_i139
#ISCELL
  mstr_standard offpage *
  page55_i14
#CELL
  mstr_discrete res *
  page55_i140
#ISCELL
  mstr_standard offpage *
  page55_i145
#ISCELL
  mstr_standard offpage *
  page55_i146
#ISCELL
  mstr_standard offpage *
  page55_i148
#ISCELL
  mstr_standard offpage *
  page55_i149
#ISCELL
  mstr_standard offpage *
  page55_i15
#ISCELL
  mstr_standard offpage *
  page55_i150
#ISCELL
  mstr_standard offpage *
  page55_i151
#CELL
  chpset_lib socket_p_mech_a *
  page55_i152
#CELL
  chpset_lib socket_p_mech_a *
  page55_i153
#CELL
  mstr_discrete res *
  page55_i155
#CELL
  mstr_discrete res *
  page55_i156
#CELL
  mstr_discrete res *
  page55_i157
#CELL
  mstr_discrete res *
  page55_i158
#CELL
  mstr_discrete res *
  page55_i159
#ISCELL
  mstr_standard offpage *
  page55_i16
#CELL
  mstr_discrete res *
  page55_i160
#CELL
  mstr_discrete res *
  page55_i161
#ISCELL
  mstr_symbols p3v3_stby *
  page55_i162
#ISCELL
  mstr_standard offpage *
  page55_i163
#ISCELL
  mstr_standard offpage *
  page55_i164
#ISCELL
  mstr_standard offpage *
  page55_i165
#ISCELL
  mstr_standard offpage *
  page55_i166
#ISCELL
  mstr_standard offpage *
  page55_i167
#ISCELL
  mstr_symbols p3v3_stby *
  page55_i169
#ISCELL
  mstr_standard offpage *
  page55_i17
#CELL
  mstr_discrete res *
  page55_i170
#CELL
  chpset_lib skx_ext_b *
  page55_i172
#ISCELL
  mstr_standard offpage *
  page55_i173
#ISCELL
  mstr_standard offpage *
  page55_i174
#ISCELL
  mstr_standard offpage *
  page55_i175
#ISCELL
  mstr_standard offpage *
  page55_i178
#ISCELL
  mstr_standard offpage *
  page55_i179
#ISCELL
  mstr_standard offpage *
  page55_i18
#ISCELL
  mstr_standard offpage *
  page55_i180
#CELL
  mstr_discrete res *
  page55_i181
#ISCELL
  mstr_standard offpage *
  page55_i182
#ISCELL
  mstr_standard offpage *
  page55_i183
#ISCELL
  mstr_standard offpage *
  page55_i184
#ISCELL
  mstr_standard offpage *
  page55_i185
#ISCELL
  mstr_standard offpage *
  page55_i186
#ISCELL
  mstr_standard offpage *
  page55_i187
#ISCELL
  mstr_standard offpage *
  page55_i188
#ISCELL
  mstr_standard offpage *
  page55_i189
#CELL
  mstr_discrete res *
  page55_i19
#ISCELL
  mstr_standard offpage *
  page55_i190
#ISCELL
  mstr_standard offpage *
  page55_i191
#ISCELL
  mstr_standard offpage *
  page55_i2
#CELL
  mstr_discrete res *
  page55_i21
#ISCELL
  mstr_symbols pvccio_cpu1 *
  page55_i22
#ISCELL
  mstr_standard offpage *
  page55_i23
#CELL
  mstr_discrete res *
  page55_i24
#CELL
  mstr_discrete res *
  page55_i25
#CELL
  mstr_discrete res *
  page55_i26
#CELL
  mstr_discrete res *
  page55_i27
#CELL
  mstr_discrete res *
  page55_i28
#CELL
  mstr_discrete res *
  page55_i29
#ISCELL
  mstr_standard offpage *
  page55_i3
#ISCELL
  mstr_standard offpage *
  page55_i30
#ISCELL
  mstr_standard offpage *
  page55_i31
#ISCELL
  mstr_standard offpage *
  page55_i32
#ISCELL
  mstr_standard offpage *
  page55_i33
#ISCELL
  mstr_standard offpage *
  page55_i34
#ISCELL
  mstr_standard offpage *
  page55_i36
#ISCELL
  mstr_standard offpage *
  page55_i37
#ISCELL
  mstr_standard offpage *
  page55_i38
#ISCELL
  mstr_standard offpage *
  page55_i39
#CELL
  mstr_discrete res *
  page55_i4
#ISCELL
  mstr_standard offpage *
  page55_i40
#ISCELL
  mstr_standard offpage *
  page55_i41
#ISCELL
  mstr_standard offpage *
  page55_i42
#ISCELL
  mstr_standard offpage *
  page55_i43
#ISCELL
  mstr_standard offpage *
  page55_i44
#ISCELL
  mstr_standard offpage *
  page55_i57
#ISCELL
  mstr_standard offpage *
  page55_i58
#ISCELL
  mstr_standard offpage *
  page55_i59
#ISCELL
  mstr_symbols pvccio_cpu1 *
  page55_i6
#ISCELL
  mstr_standard offpage *
  page55_i60
#ISCELL
  mstr_standard offpage *
  page55_i61
#ISCELL
  mstr_standard offpage *
  page55_i62
#ISCELL
  mstr_standard offpage *
  page55_i63
#ISCELL
  mstr_standard offpage *
  page55_i64
#ISCELL
  mstr_standard offpage *
  page55_i65
#ISCELL
  mstr_standard offpage *
  page55_i67
#ISCELL
  mstr_standard offpage *
  page55_i68
#CELL
  mstr_discrete res *
  page55_i7
#ISCELL
  mstr_standard offpage *
  page55_i70
#ISCELL
  mstr_standard offpage *
  page55_i73
#ISCELL
  mstr_standard offpage *
  page55_i8
#ISCELL
  mstr_standard offpage *
  page55_i80
#ISCELL
  mstr_standard offpage *
  page55_i81
#ISCELL
  mstr_standard offpage *
  page55_i82
#ISCELL
  mstr_standard offpage *
  page55_i83
